(kicad_pcb
	(version 20260206)
	(generator "pcbnew")
	(generator_version "10.0")
	(general
		(thickness 1.6)
		(legacy_teardrops no)
	)
	(paper "A4")
	(title_block
		(title "Wiwynn_Tioga_Pass_MB.brd")
		(comment 1 "Tioga Pass / footprints 4039-4044 of 4770")
	)
	(layers
		(0 "F.Cu" signal "TOP")
		(4 "In1.Cu" signal "L2GND")
		(6 "In2.Cu" signal "L3")
		(8 "In3.Cu" signal "L4GND")
		(10 "In4.Cu" signal "L5")
		(12 "In5.Cu" signal "L6GND")
		(14 "In6.Cu" signal "L7VCC")
		(16 "In7.Cu" signal "L8VCC")
		(18 "In8.Cu" signal "L9GND")
		(20 "In9.Cu" signal "L10")
		(22 "In10.Cu" signal "L11GND")
		(24 "In11.Cu" signal "L12")
		(26 "In12.Cu" signal "L13GND")
		(2 "B.Cu" signal "BOTTOM")
		(9 "F.Adhes" user "F.Adhesive")
		(11 "B.Adhes" user "B.Adhesive")
		(13 "F.Paste" user "Package Geometry/Pastemask Top")
		(15 "B.Paste" user "Package Geometry/Pastemask Bottom")
		(5 "F.SilkS" user "Ref Des/Silkscreen Top")
		(7 "B.SilkS" user "Ref Des/Silkscreen Bottom")
		(1 "F.Mask" user "Board Geometry/Soldermask Top")
		(3 "B.Mask" user "Board Geometry/Soldermask Bottom")
		(17 "Dwgs.User" user "User.Drawings")
		(19 "Cmts.User" user "User.Comments")
		(21 "Eco1.User" user "User.Eco1")
		(23 "Eco2.User" user "User.Eco2")
		(25 "Edge.Cuts" user "Board Geometry/Outline")
		(27 "Margin" user)
		(31 "F.CrtYd" user "Package Geometry/Place Bound Top")
		(29 "B.CrtYd" user "Package Geometry/Place Bound Bottom")
		(35 "F.Fab" user "Ref Des/Assembly Top")
		(33 "B.Fab" user "Ref Des/Assembly Bottom")
	)
	(footprint ""
		(layer "B.Cu")
		(at 358.44988 -77.923136)
		(property "Reference" "C3P41"
			(at 0 0 0)
			(layer "B.SilkS")
			(hide yes)
			(effects
				(font
					(size 1.27 1.27)
				)
				(justify mirror)
			)
		)
		(property "Value" ""
			(at 0 0 0)
			(layer "B.Fab")
			(effects
				(font
					(size 1.27 1.27)
				)
				(justify mirror)
			)
		)
		(duplicate_pad_numbers_are_jumpers no)
		(fp_poly
			(pts
				(xy -0.3048 -0.1016) (xy -0.3048 0.9906) (xy 0.3048 0.9906) (xy 0.3048 -0.1016)
			)
			(stroke
				(width 0)
				(type default)
			)
			(fill no)
			(layer "B.CrtYd")
		)
		(fp_line
			(start -0.3048 -0.1016)
			(end 0.3048 -0.1016)
			(stroke
				(width 0.1)
				(type default)
			)
			(layer "B.Fab")
		)
		(fp_line
			(start -0.3048 0.9906)
			(end -0.3048 -0.1016)
			(stroke
				(width 0.1)
				(type default)
			)
			(layer "B.Fab")
		)
		(fp_line
			(start 0.3048 -0.1016)
			(end 0.3048 0.9906)
			(stroke
				(width 0.1)
				(type default)
			)
			(layer "B.Fab")
		)
		(fp_line
			(start 0.3048 0.9906)
			(end -0.3048 0.9906)
			(stroke
				(width 0.1)
				(type default)
			)
			(layer "B.Fab")
		)
		(pad "1" smd rect
			(at 0 0 180)
			(size 0.508 0.508)
			(layers "B.Cu" "B.Mask" "B.Paste")
			(net "P3E_CPU0_PE1_SS_TXN<7>")
		)
		(pad "2" smd rect
			(at 0 0.889 180)
			(size 0.508 0.508)
			(layers "B.Cu" "B.Mask" "B.Paste")
			(net "P3E_CPU0_PE1_SS_C_TXN<7>")
		)
		(zone
			(layer "B.Cu")
			(hatch none 0.5)
			(connect_pads
				(clearance 0)
			)
			(min_thickness 0.25)
			(keepout
				(tracks allowed)
				(vias not_allowed)
				(pads allowed)
				(copperpour not_allowed)
				(footprints allowed)
			)
			(placement
				(enabled no)
				(sheetname "")
			)
			(fill
				(thermal_gap 0.5)
				(thermal_bridge_width 0.5)
				(island_removal_mode 0)
			)
			(polygon
				(pts
					(xy 358.70388 -77.669136) (xy 358.19588 -77.669136) (xy 358.19588 -77.288136) (xy 358.70388 -77.288136)
				)
			)
		)
		(zone
			(layer "B.Cu")
			(hatch none 0.5)
			(connect_pads
				(clearance 0)
			)
			(min_thickness 0.25)
			(keepout
				(tracks not_allowed)
				(vias allowed)
				(pads allowed)
				(copperpour not_allowed)
				(footprints allowed)
			)
			(placement
				(enabled no)
				(sheetname "")
			)
			(fill
				(thermal_gap 0.5)
				(thermal_bridge_width 0.5)
				(island_removal_mode 0)
			)
			(polygon
				(pts
					(xy 358.70388 -77.288136) (xy 358.19588 -77.288136) (xy 358.19588 -77.669136) (xy 358.70388 -77.669136)
				)
			)
		)
	)
	(footprint ""
		(layer "B.Cu")
		(at 17.907 -46.482 -90)
		(property "Reference" "R9R6"
			(at 0 0 90)
			(layer "B.SilkS")
			(hide yes)
			(effects
				(font
					(size 1.27 1.27)
				)
				(justify mirror)
			)
		)
		(property "Value" ""
			(at 0 0 90)
			(layer "B.Fab")
			(effects
				(font
					(size 1.27 1.27)
				)
				(justify mirror)
			)
		)
		(duplicate_pad_numbers_are_jumpers no)
		(fp_poly
			(pts
				(xy 0.2794 -0.1016) (xy -0.2794 -0.1016) (xy -0.2794 0.9906) (xy 0.2794 0.9906)
			)
			(stroke
				(width 0)
				(type default)
			)
			(fill no)
			(layer "B.CrtYd")
		)
		(fp_line
			(start -0.2794 0.9906)
			(end -0.2794 -0.1016)
			(stroke
				(width 0.1)
				(type default)
			)
			(layer "B.Fab")
		)
		(fp_line
			(start 0.2794 0.9906)
			(end -0.2794 0.9906)
			(stroke
				(width 0.1)
				(type default)
			)
			(layer "B.Fab")
		)
		(fp_line
			(start -0.2794 -0.1016)
			(end 0.2794 -0.1016)
			(stroke
				(width 0.1)
				(type default)
			)
			(layer "B.Fab")
		)
		(fp_line
			(start 0.2794 -0.1016)
			(end 0.2794 0.9906)
			(stroke
				(width 0.1)
				(type default)
			)
			(layer "B.Fab")
		)
		(pad "1" smd rect
			(at 0 0 90)
			(size 0.508 0.508)
			(layers "B.Cu" "B.Mask" "B.Paste")
			(net "ISENSE_TMP421_2_BC")
		)
		(pad "2" smd rect
			(at 0 0.889 90)
			(size 0.508 0.508)
			(layers "B.Cu" "B.Mask" "B.Paste")
			(net "ISENSE_TMP421_2_DXN")
		)
		(zone
			(layer "B.Cu")
			(hatch none 0.5)
			(connect_pads
				(clearance 0)
			)
			(min_thickness 0.25)
			(keepout
				(tracks not_allowed)
				(vias allowed)
				(pads allowed)
				(copperpour not_allowed)
				(footprints allowed)
			)
			(placement
				(enabled no)
				(sheetname "")
			)
			(fill
				(thermal_gap 0.5)
				(thermal_bridge_width 0.5)
				(island_removal_mode 0)
			)
			(polygon
				(pts
					(xy 17.272 -46.228) (xy 17.272 -46.736) (xy 17.653 -46.736) (xy 17.653 -46.228)
				)
			)
		)
		(zone
			(layer "B.Cu")
			(hatch none 0.5)
			(connect_pads
				(clearance 0)
			)
			(min_thickness 0.25)
			(keepout
				(tracks allowed)
				(vias not_allowed)
				(pads allowed)
				(copperpour not_allowed)
				(footprints allowed)
			)
			(placement
				(enabled no)
				(sheetname "")
			)
			(fill
				(thermal_gap 0.5)
				(thermal_bridge_width 0.5)
				(island_removal_mode 0)
			)
			(polygon
				(pts
					(xy 17.653 -46.228) (xy 17.653 -46.736) (xy 17.272 -46.736) (xy 17.272 -46.228)
				)
			)
		)
	)
	(footprint ""
		(layer "B.Cu")
		(at 476.1865 -117.6655 90)
		(property "Reference" "Q1W1"
			(at 0.229362 -1.2065 90)
			(unlocked yes)
			(layer "B.SilkS")
			(effects
				(font
					(size 0.4064 0.254)
					(thickness 0.1524)
				)
				(justify left mirror)
			)
		)
		(property "Value" ""
			(at 0 0 90)
			(layer "B.Fab")
			(effects
				(font
					(size 1.27 1.27)
				)
				(justify mirror)
			)
		)
		(duplicate_pad_numbers_are_jumpers no)
		(fp_line
			(start -0.9525 -0.5715)
			(end -1.778 -0.5715)
			(stroke
				(width 0.1524)
				(type default)
			)
			(layer "B.SilkS")
		)
		(fp_line
			(start -1.778 -0.5715)
			(end -1.778 0.3175)
			(stroke
				(width 0.1524)
				(type default)
			)
			(layer "B.SilkS")
		)
		(fp_line
			(start -0.381 0.635)
			(end -0.381 1.27)
			(stroke
				(width 0.1524)
				(type default)
			)
			(layer "B.SilkS")
		)
		(fp_line
			(start -0.9525 2.4765)
			(end -1.778 2.4765)
			(stroke
				(width 0.1524)
				(type default)
			)
			(layer "B.SilkS")
		)
		(fp_line
			(start -1.778 2.4765)
			(end -1.778 1.5875)
			(stroke
				(width 0.1524)
				(type default)
			)
			(layer "B.SilkS")
		)
		(fp_circle
			(center 0.9525 -0.9271)
			(end 0.9525 -0.8001)
			(stroke
				(width 0.254)
				(type default)
			)
			(fill no)
			(layer "B.SilkS")
		)
		(fp_poly
			(pts
				(xy -1.778 2.4765) (xy -0.381 2.4765) (xy -0.381 -0.5715) (xy -1.778 -0.5715)
			)
			(stroke
				(width 0)
				(type default)
			)
			(fill no)
			(layer "B.CrtYd")
		)
		(fp_line
			(start -0.381 -0.5715)
			(end -0.381 2.4765)
			(stroke
				(width 0.1)
				(type default)
			)
			(layer "B.Fab")
		)
		(fp_line
			(start -1.778 -0.5715)
			(end -0.381 -0.5715)
			(stroke
				(width 0.1)
				(type default)
			)
			(layer "B.Fab")
		)
		(fp_line
			(start -0.381 2.4765)
			(end -1.778 2.4765)
			(stroke
				(width 0.1)
				(type default)
			)
			(layer "B.Fab")
		)
		(fp_line
			(start -1.778 2.4765)
			(end -1.778 -0.5715)
			(stroke
				(width 0.1)
				(type default)
			)
			(layer "B.Fab")
		)
		(fp_circle
			(center 0.9525 -0.9271)
			(end 0.9525 -0.8001)
			(stroke
				(width 0.254)
				(type default)
			)
			(fill no)
			(layer "B.Fab")
		)
		(pad "1" smd rect
			(at 0 0 270)
			(size 1.143 0.508)
			(layers "B.Cu" "B.Mask" "B.Paste")
			(net "FM_OCP_MEZZA_PRES_N")
		)
		(pad "2" smd rect
			(at 0 1.905 270)
			(size 1.143 0.508)
			(layers "B.Cu" "B.Mask" "B.Paste")
			(net "GND")
		)
		(pad "3" smd rect
			(at -2.159 0.9525 270)
			(size 1.143 0.508)
			(layers "B.Cu" "B.Mask" "B.Paste")
			(net "FM_OCP_MEZZA_PRES")
		)
	)
	(footprint ""
		(layer "B.Cu")
		(at 369.8875 -55.16372)
		(property "Reference" "U3P1"
			(at -4.578096 -1.320292 180)
			(unlocked yes)
			(layer "B.SilkS")
			(effects
				(font
					(size 0.7874 0.5842)
					(thickness 0.1524)
				)
				(justify left mirror)
			)
		)
		(property "Value" ""
			(at 0 0 0)
			(layer "B.Fab")
			(effects
				(font
					(size 1.27 1.27)
				)
				(justify mirror)
			)
		)
		(duplicate_pad_numbers_are_jumpers no)
		(fp_line
			(start -4.4323 -0.64008)
			(end -4.4323 4.52628)
			(stroke
				(width 0.1524)
				(type default)
			)
			(layer "B.SilkS")
		)
		(fp_line
			(start -4.4323 4.52628)
			(end -1.5367 4.52628)
			(stroke
				(width 0.1524)
				(type default)
			)
			(layer "B.SilkS")
		)
		(fp_line
			(start -3.302 0.49022)
			(end -3.302 -0.64008)
			(stroke
				(width 0.1524)
				(type default)
			)
			(layer "B.SilkS")
		)
		(fp_line
			(start -2.667 -0.64008)
			(end -2.667 0.49022)
			(stroke
				(width 0.1524)
				(type default)
			)
			(layer "B.SilkS")
		)
		(fp_line
			(start -2.667 0.49022)
			(end -3.302 0.49022)
			(stroke
				(width 0.1524)
				(type default)
			)
			(layer "B.SilkS")
		)
		(fp_line
			(start -1.5367 -0.64008)
			(end -4.4323 -0.64008)
			(stroke
				(width 0.1524)
				(type default)
			)
			(layer "B.SilkS")
		)
		(fp_line
			(start -1.5367 4.52628)
			(end -1.5367 -0.64008)
			(stroke
				(width 0.1524)
				(type default)
			)
			(layer "B.SilkS")
		)
		(fp_circle
			(center 1.104138 -0.684784)
			(end 1.231138 -0.684784)
			(stroke
				(width 0.254)
				(type default)
			)
			(fill no)
			(layer "B.SilkS")
		)
		(fp_poly
			(pts
				(xy -0.7366 4.54152) (xy -0.7366 -0.64008) (xy -4.7244 -0.64008) (xy -5.2324 -0.64008) (xy -5.2324 4.54152)
				(xy -4.7244 4.54152)
			)
			(stroke
				(width 0)
				(type default)
			)
			(fill no)
			(layer "B.CrtYd")
		)
		(fp_line
			(start -5.2324 -0.64008)
			(end -5.2324 4.54152)
			(stroke
				(width 0.1)
				(type default)
			)
			(layer "B.Fab")
		)
		(fp_line
			(start -5.2324 4.54152)
			(end -0.7366 4.54152)
			(stroke
				(width 0.1)
				(type default)
			)
			(layer "B.Fab")
		)
		(fp_line
			(start -3.302 0.49022)
			(end -3.302 -0.64008)
			(stroke
				(width 0.1)
				(type default)
			)
			(layer "B.Fab")
		)
		(fp_line
			(start -2.667 -0.64008)
			(end -2.667 0.49022)
			(stroke
				(width 0.1)
				(type default)
			)
			(layer "B.Fab")
		)
		(fp_line
			(start -2.667 0.49022)
			(end -3.302 0.49022)
			(stroke
				(width 0.1)
				(type default)
			)
			(layer "B.Fab")
		)
		(fp_line
			(start -0.7366 -0.64008)
			(end -5.2324 -0.64008)
			(stroke
				(width 0.1)
				(type default)
			)
			(layer "B.Fab")
		)
		(fp_line
			(start -0.7366 4.54152)
			(end -0.7366 -0.64008)
			(stroke
				(width 0.1)
				(type default)
			)
			(layer "B.Fab")
		)
		(fp_circle
			(center 1.612138 -0.684784)
			(end 1.739138 -0.684784)
			(stroke
				(width 0.254)
				(type default)
			)
			(fill no)
			(layer "B.Fab")
		)
		(pad "1" smd rect
			(at 0 0 180)
			(size 2.159 0.381)
			(layers "B.Cu" "B.Mask" "B.Paste")
			(net "PU_GTL2014_1_DIR")
		)
		(pad "2" smd rect
			(at 0 0.65024 180)
			(size 2.159 0.381)
			(layers "B.Cu" "B.Mask" "B.Paste")
			(net "PWRGD_CPU0_DRAMPWROK_DEF_G")
		)
		(pad "3" smd rect
			(at 0 1.30048 180)
			(size 2.159 0.381)
			(layers "B.Cu" "B.Mask" "B.Paste")
			(net "PWRGD_CPU0_DRAMPWROK_ABC_G")
		)
		(pad "4" smd rect
			(at 0 1.95072 180)
			(size 2.159 0.381)
			(layers "B.Cu" "B.Mask" "B.Paste")
			(net "PD_GTL2014_1_VREF")
		)
		(pad "5" smd rect
			(at 0 2.60096 180)
			(size 2.159 0.381)
			(layers "B.Cu" "B.Mask" "B.Paste")
			(net "RST_CPU0_G_N")
		)
		(pad "6" smd rect
			(at 0 3.2512 180)
			(size 2.159 0.381)
			(layers "B.Cu" "B.Mask" "B.Paste")
			(net "PWRGD_CPU0_G")
		)
		(pad "7" smd rect
			(at 0 3.90144 180)
			(size 2.159 0.381)
			(layers "B.Cu" "B.Mask" "B.Paste")
			(net "GND")
		)
		(pad "8" smd rect
			(at -5.969 3.90144 180)
			(size 2.159 0.381)
			(layers "B.Cu" "B.Mask" "B.Paste")
			(net "GND")
		)
		(pad "9" smd rect
			(at -5.969 3.2512 180)
			(size 2.159 0.381)
			(layers "B.Cu" "B.Mask" "B.Paste")
			(net "PWRGD_CPU0_LVC3")
		)
		(pad "10" smd rect
			(at -5.969 2.60096 180)
			(size 2.159 0.381)
			(layers "B.Cu" "B.Mask" "B.Paste")
			(net "RST_CPU0_LVC3_N")
		)
		(pad "11" smd rect
			(at -5.969 1.95072 180)
			(size 2.159 0.381)
			(layers "B.Cu" "B.Mask" "B.Paste")
			(net "GND")
		)
		(pad "12" smd rect
			(at -5.969 1.30048 180)
			(size 2.159 0.381)
			(layers "B.Cu" "B.Mask" "B.Paste")
			(net "PWRGD_DRAMPWRGD")
		)
		(pad "13" smd rect
			(at -5.969 0.65024 180)
			(size 2.159 0.381)
			(layers "B.Cu" "B.Mask" "B.Paste")
			(net "PWRGD_DRAMPWRGD")
		)
		(pad "14" smd rect
			(at -5.969 0 180)
			(size 2.159 0.381)
			(layers "B.Cu" "B.Mask" "B.Paste")
			(net "P3V3_STBY")
		)
	)
	(footprint ""
		(layer "B.Cu")
		(at 274.881086 -85.06714)
		(property "Reference" "C5P3"
			(at 0 0 0)
			(layer "B.SilkS")
			(hide yes)
			(effects
				(font
					(size 1.27 1.27)
				)
				(justify mirror)
			)
		)
		(property "Value" ""
			(at 0 0 0)
			(layer "B.Fab")
			(effects
				(font
					(size 1.27 1.27)
				)
				(justify mirror)
			)
		)
		(duplicate_pad_numbers_are_jumpers no)
		(fp_poly
			(pts
				(xy 0.7239 -0.2159) (xy -0.7239 -0.2159) (xy -0.7239 1.9939) (xy 0.7239 1.9939)
			)
			(stroke
				(width 0)
				(type default)
			)
			(fill no)
			(layer "B.CrtYd")
		)
		(fp_line
			(start -0.7239 -0.2159)
			(end 0.7239 -0.2159)
			(stroke
				(width 0.1)
				(type default)
			)
			(layer "B.Fab")
		)
		(fp_line
			(start -0.7239 1.9939)
			(end -0.7239 -0.2159)
			(stroke
				(width 0.1)
				(type default)
			)
			(layer "B.Fab")
		)
		(fp_line
			(start 0.7239 -0.2159)
			(end 0.7239 1.9939)
			(stroke
				(width 0.1)
				(type default)
			)
			(layer "B.Fab")
		)
		(fp_line
			(start 0.7239 1.9939)
			(end -0.7239 1.9939)
			(stroke
				(width 0.1)
				(type default)
			)
			(layer "B.Fab")
		)
		(pad "1" smd rect
			(at 0 0 180)
			(size 1.27 1.016)
			(layers "B.Cu" "B.Mask" "B.Paste")
			(net "PVDDQ_DEF")
		)
		(pad "2" smd rect
			(at 0 1.778 180)
			(size 1.27 1.016)
			(layers "B.Cu" "B.Mask" "B.Paste")
			(net "GND")
		)
		(zone
			(layer "B.Cu")
			(hatch none 0.5)
			(connect_pads
				(clearance 0)
			)
			(min_thickness 0.25)
			(keepout
				(tracks not_allowed)
				(vias allowed)
				(pads allowed)
				(copperpour not_allowed)
				(footprints allowed)
			)
			(placement
				(enabled no)
				(sheetname "")
			)
			(fill
				(thermal_gap 0.5)
				(thermal_bridge_width 0.5)
				(island_removal_mode 0)
			)
			(polygon
				(pts
					(xy 275.516086 -84.55914) (xy 274.246086 -84.55914) (xy 274.246086 -83.79714) (xy 275.516086 -83.79714)
				)
			)
		)
	)
	(footprint ""
		(layer "B.Cu")
		(at 494.4872 -137.7696 180)
		(property "Reference" "R1L30"
			(at 0 0 0)
			(layer "B.SilkS")
			(hide yes)
			(effects
				(font
					(size 1.27 1.27)
				)
				(justify mirror)
			)
		)
		(property "Value" ""
			(at 0 0 0)
			(layer "B.Fab")
			(effects
				(font
					(size 1.27 1.27)
				)
				(justify mirror)
			)
		)
		(duplicate_pad_numbers_are_jumpers no)
		(fp_poly
			(pts
				(xy 0.2794 -0.1016) (xy -0.2794 -0.1016) (xy -0.2794 0.9906) (xy 0.2794 0.9906)
			)
			(stroke
				(width 0)
				(type default)
			)
			(fill no)
			(layer "B.CrtYd")
		)
		(fp_line
			(start 0.2794 0.9906)
			(end -0.2794 0.9906)
			(stroke
				(width 0.1)
				(type default)
			)
			(layer "B.Fab")
		)
		(fp_line
			(start 0.2794 -0.1016)
			(end 0.2794 0.9906)
			(stroke
				(width 0.1)
				(type default)
			)
			(layer "B.Fab")
		)
		(fp_line
			(start -0.2794 0.9906)
			(end -0.2794 -0.1016)
			(stroke
				(width 0.1)
				(type default)
			)
			(layer "B.Fab")
		)
		(fp_line
			(start -0.2794 -0.1016)
			(end 0.2794 -0.1016)
			(stroke
				(width 0.1)
				(type default)
			)
			(layer "B.Fab")
		)
		(pad "1" smd rect
			(at 0 0)
			(size 0.508 0.508)
			(layers "B.Cu" "B.Mask" "B.Paste")
			(net "LED_POSTCODE_1")
		)
		(pad "2" smd rect
			(at 0 0.889)
			(size 0.508 0.508)
			(layers "B.Cu" "B.Mask" "B.Paste")
			(net "LED_POSTCODE_1_R")
		)
		(zone
			(layer "B.Cu")
			(hatch none 0.5)
			(connect_pads
				(clearance 0)
			)
			(min_thickness 0.25)
			(keepout
				(tracks not_allowed)
				(vias allowed)
				(pads allowed)
				(copperpour not_allowed)
				(footprints allowed)
			)
			(placement
				(enabled no)
				(sheetname "")
			)
			(fill
				(thermal_gap 0.5)
				(thermal_bridge_width 0.5)
				(island_removal_mode 0)
			)
			(polygon
				(pts
					(xy 494.2332 -138.4046) (xy 494.7412 -138.4046) (xy 494.7412 -138.0236) (xy 494.2332 -138.0236)
				)
			)
		)
		(zone
			(layer "B.Cu")
			(hatch none 0.5)
			(connect_pads
				(clearance 0)
			)
			(min_thickness 0.25)
			(keepout
				(tracks allowed)
				(vias not_allowed)
				(pads allowed)
				(copperpour not_allowed)
				(footprints allowed)
			)
			(placement
				(enabled no)
				(sheetname "")
			)
			(fill
				(thermal_gap 0.5)
				(thermal_bridge_width 0.5)
				(island_removal_mode 0)
			)
			(polygon
				(pts
					(xy 494.2332 -138.0236) (xy 494.7412 -138.0236) (xy 494.7412 -138.4046) (xy 494.2332 -138.4046)
				)
			)
		)
	)
)
